# T6G (Grand Teton) — schematic netlist excerpt (pin names and nets, part order shuffled) for the footprints in the layout excerpt that follows; sources: Cadence DE-HDL packaged netlist, KiCad conversion of 04192023_DAF0TMB3IC0_F0TG_MB_C_brd_V02_OCP.brd

R3474  Q_RES  4.7K 5% CHIP  pkg 0402LF  page 126 : A = P3V3_AUX ; B = GPU_PRSNT
C238  Q_CAP  10PF 50V 1% NPO  pkg 0402  page 55 : A = XTAL_CPU1_R_X32K_X1 ; B = GND
PC459_1  Q_CAP  22UF 4V 20% X6S  pkg C0805  page 222 : A = PVDDIO_P1 ; B = GND

(kicad_pcb
	(version 20260206)
	(generator "pcbnew")
	(generator_version "10.0")
	(general
		(thickness 1.6)
		(legacy_teardrops no)
	)
	(paper "A4")
	(title_block
		(title "04192023_DAF0TMB3IC0_F0TG_MB_C_brd_V02_OCP.brd")
		(comment 1 "Grand Teton / footprints 6224-6226 of 8354")
	)
	(layers
		(0 "F.Cu" signal "TOP")
		(4 "In1.Cu" signal "GND")
		(6 "In2.Cu" signal "IN1")
		(8 "In3.Cu" signal "GND1")
		(10 "In4.Cu" signal "IN2")
		(12 "In5.Cu" signal "GND2")
		(14 "In6.Cu" signal "IN3")
		(16 "In7.Cu" signal "GND3")
		(18 "In8.Cu" signal "VCC")
		(20 "In9.Cu" signal "VCC1")
		(22 "In10.Cu" signal "GND4")
		(24 "In11.Cu" signal "IN4")
		(26 "In12.Cu" signal "GND5")
		(28 "In13.Cu" signal "IN5")
		(30 "In14.Cu" signal "GND6")
		(32 "In15.Cu" signal "IN6")
		(34 "In16.Cu" signal "GND7")
		(2 "B.Cu" signal "BOTTOM")
		(9 "F.Adhes" user "F.Adhesive")
		(11 "B.Adhes" user "B.Adhesive")
		(13 "F.Paste" user "Package Geometry/Pastemask Top")
		(15 "B.Paste" user "Package Geometry/Pastemask Bottom")
		(5 "F.SilkS" user "Ref Des/Silkscreen Top")
		(7 "B.SilkS" user "Ref Des/Silkscreen Bottom")
		(1 "F.Mask" user "Board Geometry/Soldermask Top")
		(3 "B.Mask" user "Board Geometry/Soldermask Bottom")
		(17 "Dwgs.User" user "User.Drawings")
		(19 "Cmts.User" user "User.Comments")
		(21 "Eco1.User" user "User.Eco1")
		(23 "Eco2.User" user "User.Eco2")
		(25 "Edge.Cuts" user "Board Geometry/Outline")
		(27 "Margin" user)
		(31 "F.CrtYd" user "Package Geometry/Place Bound Top")
		(29 "B.CrtYd" user "Package Geometry/Place Bound Bottom")
		(35 "F.Fab" user "Ref Des/Assembly Top")
		(33 "B.Fab" user "Ref Des/Assembly Bottom")
	)
	(footprint ""
		(layer "B.Cu")
		(at 46.359318 -430.165002 90)
		(property "Reference" "R3474"
			(at 0 0 90)
			(layer "B.SilkS")
			(hide yes)
			(effects
				(font
					(size 1.27 1.27)
				)
				(justify mirror)
			)
		)
		(property "Value" ""
			(at 0 0 90)
			(layer "B.Fab")
			(effects
				(font
					(size 1.27 1.27)
				)
				(justify mirror)
			)
		)
		(duplicate_pad_numbers_are_jumpers no)
		(fp_line
			(start 0.7874 -0.4064)
			(end -0.7874 -0.4064)
			(stroke
				(width 0.1524)
				(type default)
			)
			(layer "B.SilkS")
		)
		(fp_line
			(start -0.7874 -0.4064)
			(end -0.7874 0.4064)
			(stroke
				(width 0.1524)
				(type default)
			)
			(layer "B.SilkS")
		)
		(fp_line
			(start 0.7874 0.4064)
			(end 0.7874 -0.4064)
			(stroke
				(width 0.1524)
				(type default)
			)
			(layer "B.SilkS")
		)
		(fp_line
			(start -0.7874 0.4064)
			(end 0.7874 0.4064)
			(stroke
				(width 0.1524)
				(type default)
			)
			(layer "B.SilkS")
		)
		(fp_line
			(start 0.67945 -0.305054)
			(end 0.12065 -0.305054)
			(stroke
				(width 0.1)
				(type default)
			)
			(layer "B.Fab")
		)
		(fp_line
			(start 0.12065 -0.305054)
			(end 0.12065 -0.2794)
			(stroke
				(width 0.1)
				(type default)
			)
			(layer "B.Fab")
		)
		(fp_line
			(start -0.12065 -0.3048)
			(end -0.67945 -0.3048)
			(stroke
				(width 0.1)
				(type default)
			)
			(layer "B.Fab")
		)
		(fp_line
			(start -0.67945 -0.3048)
			(end -0.67945 0.3048)
			(stroke
				(width 0.1)
				(type default)
			)
			(layer "B.Fab")
		)
		(fp_line
			(start 0.12065 -0.2794)
			(end -0.12065 -0.2794)
			(stroke
				(width 0.1)
				(type default)
			)
			(layer "B.Fab")
		)
		(fp_line
			(start -0.12065 -0.2794)
			(end -0.12065 -0.3048)
			(stroke
				(width 0.1)
				(type default)
			)
			(layer "B.Fab")
		)
		(fp_line
			(start 0.12065 0.2794)
			(end 0.12065 0.3048)
			(stroke
				(width 0.1)
				(type default)
			)
			(layer "B.Fab")
		)
		(fp_line
			(start -0.120396 0.2794)
			(end 0.12065 0.2794)
			(stroke
				(width 0.1)
				(type default)
			)
			(layer "B.Fab")
		)
		(fp_line
			(start 0.67945 0.3048)
			(end 0.67945 -0.305054)
			(stroke
				(width 0.1)
				(type default)
			)
			(layer "B.Fab")
		)
		(fp_line
			(start 0.12065 0.3048)
			(end 0.67945 0.3048)
			(stroke
				(width 0.1)
				(type default)
			)
			(layer "B.Fab")
		)
		(fp_line
			(start -0.120396 0.3048)
			(end -0.120396 0.2794)
			(stroke
				(width 0.1)
				(type default)
			)
			(layer "B.Fab")
		)
		(fp_line
			(start -0.67945 0.3048)
			(end -0.120396 0.3048)
			(stroke
				(width 0.1)
				(type default)
			)
			(layer "B.Fab")
		)
		(pad "1" smd circle
			(at 0.40005 0 270)
			(size 0 0)
			(layers "B.Cu" "B.Mask" "B.Paste")
			(net "P3V3_AUX")
		)
		(pad "2" smd circle
			(at -0.40005 0 270)
			(size 0 0)
			(layers "B.Cu" "B.Mask" "B.Paste")
			(net "GPU_PRSNT")
		)
	)
	(footprint ""
		(layer "B.Cu")
		(at 151.884634 -316.353952 90)
		(property "Reference" "C238"
			(at 0 0 90)
			(layer "B.SilkS")
			(hide yes)
			(effects
				(font
					(size 1.27 1.27)
				)
				(justify mirror)
			)
		)
		(property "Value" ""
			(at 0 0 90)
			(layer "B.Fab")
			(effects
				(font
					(size 1.27 1.27)
				)
				(justify mirror)
			)
		)
		(duplicate_pad_numbers_are_jumpers no)
		(fp_line
			(start 0.7874 -0.4064)
			(end -0.7874 -0.4064)
			(stroke
				(width 0.1524)
				(type default)
			)
			(layer "B.SilkS")
		)
		(fp_line
			(start -0.7874 -0.4064)
			(end -0.7874 0.4064)
			(stroke
				(width 0.1524)
				(type default)
			)
			(layer "B.SilkS")
		)
		(fp_line
			(start 0.7874 0.4064)
			(end 0.7874 -0.4064)
			(stroke
				(width 0.1524)
				(type default)
			)
			(layer "B.SilkS")
		)
		(fp_line
			(start -0.7874 0.4064)
			(end 0.7874 0.4064)
			(stroke
				(width 0.1524)
				(type default)
			)
			(layer "B.SilkS")
		)
		(fp_line
			(start 0.67945 -0.305054)
			(end 0.12065 -0.305054)
			(stroke
				(width 0.1)
				(type default)
			)
			(layer "B.Fab")
		)
		(fp_line
			(start 0.12065 -0.305054)
			(end 0.12065 -0.2794)
			(stroke
				(width 0.1)
				(type default)
			)
			(layer "B.Fab")
		)
		(fp_line
			(start -0.12065 -0.3048)
			(end -0.67945 -0.3048)
			(stroke
				(width 0.1)
				(type default)
			)
			(layer "B.Fab")
		)
		(fp_line
			(start -0.67945 -0.3048)
			(end -0.67945 0.3048)
			(stroke
				(width 0.1)
				(type default)
			)
			(layer "B.Fab")
		)
		(fp_line
			(start 0.12065 -0.2794)
			(end -0.12065 -0.2794)
			(stroke
				(width 0.1)
				(type default)
			)
			(layer "B.Fab")
		)
		(fp_line
			(start -0.12065 -0.2794)
			(end -0.12065 -0.3048)
			(stroke
				(width 0.1)
				(type default)
			)
			(layer "B.Fab")
		)
		(fp_line
			(start 0.12065 0.2794)
			(end 0.12065 0.3048)
			(stroke
				(width 0.1)
				(type default)
			)
			(layer "B.Fab")
		)
		(fp_line
			(start -0.120396 0.2794)
			(end 0.12065 0.2794)
			(stroke
				(width 0.1)
				(type default)
			)
			(layer "B.Fab")
		)
		(fp_line
			(start 0.67945 0.3048)
			(end 0.67945 -0.305054)
			(stroke
				(width 0.1)
				(type default)
			)
			(layer "B.Fab")
		)
		(fp_line
			(start 0.12065 0.3048)
			(end 0.67945 0.3048)
			(stroke
				(width 0.1)
				(type default)
			)
			(layer "B.Fab")
		)
		(fp_line
			(start -0.120396 0.3048)
			(end -0.120396 0.2794)
			(stroke
				(width 0.1)
				(type default)
			)
			(layer "B.Fab")
		)
		(fp_line
			(start -0.67945 0.3048)
			(end -0.120396 0.3048)
			(stroke
				(width 0.1)
				(type default)
			)
			(layer "B.Fab")
		)
		(pad "1" smd circle
			(at 0.40005 0 270)
			(size 0 0)
			(layers "B.Cu" "B.Mask" "B.Paste")
			(net "XTAL_CPU1_R_X32K_X1")
		)
		(pad "2" smd circle
			(at -0.40005 0 270)
			(size 0 0)
			(layers "B.Cu" "B.Mask" "B.Paste")
			(net "GND")
		)
	)
	(footprint ""
		(layer "B.Cu")
		(at 47.417228 -337.989672 -90)
		(property "Reference" "PC459_1"
			(at 0 0 90)
			(layer "B.SilkS")
			(hide yes)
			(effects
				(font
					(size 1.27 1.27)
				)
				(justify mirror)
			)
		)
		(property "Value" ""
			(at 0 0 90)
			(layer "B.Fab")
			(effects
				(font
					(size 1.27 1.27)
				)
				(justify mirror)
			)
		)
		(duplicate_pad_numbers_are_jumpers no)
		(fp_line
			(start -1.524 0.762)
			(end 1.524 0.762)
			(stroke
				(width 0.1524)
				(type default)
			)
			(layer "B.SilkS")
		)
		(fp_line
			(start 1.524 0.762)
			(end 1.524 -0.762)
			(stroke
				(width 0.1524)
				(type default)
			)
			(layer "B.SilkS")
		)
		(fp_line
			(start -1.524 -0.762)
			(end -1.524 0.762)
			(stroke
				(width 0.1524)
				(type default)
			)
			(layer "B.SilkS")
		)
		(fp_line
			(start 1.524 -0.762)
			(end -1.524 -0.762)
			(stroke
				(width 0.1524)
				(type default)
			)
			(layer "B.SilkS")
		)
		(fp_line
			(start -1.1049 0.724916)
			(end -1.1049 -0.724916)
			(stroke
				(width 0.1)
				(type default)
			)
			(layer "B.Fab")
		)
		(fp_line
			(start 1.1049 0.724916)
			(end -1.1049 0.724916)
			(stroke
				(width 0.1)
				(type default)
			)
			(layer "B.Fab")
		)
		(fp_line
			(start -1.1049 -0.724916)
			(end 1.1049 -0.724916)
			(stroke
				(width 0.1)
				(type default)
			)
			(layer "B.Fab")
		)
		(fp_line
			(start 1.1049 -0.724916)
			(end 1.1049 0.724916)
			(stroke
				(width 0.1)
				(type default)
			)
			(layer "B.Fab")
		)
		(pad "1" smd rect
			(at 0.889 0 270)
			(size 1.016 1.27)
			(layers "B.Cu" "B.Mask" "B.Paste")
			(net "PVDDIO_P1")
		)
		(pad "2" smd rect
			(at -0.889 0 270)
			(size 1.016 1.27)
			(layers "B.Cu" "B.Mask" "B.Paste")
			(net "GND")
		)
	)
)
